(kicad_pcb
	(version 20260206)
	(generator "pcbnew")
	(generator_version "10.0")
	(general
		(thickness 1.6)
		(legacy_teardrops no)
	)
	(paper "A4")
	(title_block
		(title "01162023_DA0F0TEBIF0_F0T_Expander_BD_F_brd_V02_OCP.brd")
		(comment 1 "Grand Teton / footprints 236-242 of 9728")
	)
	(layers
		(0 "F.Cu" signal "TOP")
		(4 "In1.Cu" signal "GND")
		(6 "In2.Cu" signal "VCC")
		(8 "In3.Cu" signal "VCC1")
		(10 "In4.Cu" signal "GND1")
		(12 "In5.Cu" signal "IN1")
		(14 "In6.Cu" signal "GND2")
		(16 "In7.Cu" signal "IN2")
		(18 "In8.Cu" signal "GND3")
		(20 "In9.Cu" signal "IN3")
		(22 "In10.Cu" signal "GND4")
		(24 "In11.Cu" signal "IN4")
		(26 "In12.Cu" signal "GND5")
		(28 "In13.Cu" signal "IN5")
		(30 "In14.Cu" signal "GND6")
		(32 "In15.Cu" signal "IN6")
		(34 "In16.Cu" signal "GND7")
		(2 "B.Cu" signal "BOTTOM")
		(9 "F.Adhes" user "F.Adhesive")
		(11 "B.Adhes" user "B.Adhesive")
		(13 "F.Paste" user "Package Geometry/Pastemask Top")
		(15 "B.Paste" user "Package Geometry/Pastemask Bottom")
		(5 "F.SilkS" user "Ref Des/Silkscreen Top")
		(7 "B.SilkS" user "Ref Des/Silkscreen Bottom")
		(1 "F.Mask" user "Board Geometry/Soldermask Top")
		(3 "B.Mask" user "Board Geometry/Soldermask Bottom")
		(17 "Dwgs.User" user "User.Drawings")
		(19 "Cmts.User" user "User.Comments")
		(21 "Eco1.User" user "User.Eco1")
		(23 "Eco2.User" user "User.Eco2")
		(25 "Edge.Cuts" user "Board Geometry/Outline")
		(27 "Margin" user)
		(31 "F.CrtYd" user "Package Geometry/Place Bound Top")
		(29 "B.CrtYd" user "Package Geometry/Place Bound Bottom")
		(35 "F.Fab" user "Ref Des/Assembly Top")
		(33 "B.Fab" user "Ref Des/Assembly Bottom")
	)
	(footprint ""
		(layer "F.Cu")
		(at 16.445738 -394.128752 -90)
		(property "Reference" "R6755"
			(at 0 0 270)
			(layer "F.SilkS")
			(hide yes)
			(effects
				(font
					(size 1.27 1.27)
				)
			)
		)
		(property "Value" ""
			(at 0 0 270)
			(layer "F.Fab")
			(effects
				(font
					(size 1.27 1.27)
				)
			)
		)
		(duplicate_pad_numbers_are_jumpers no)
		(fp_line
			(start -0.7874 0.4064)
			(end -0.7874 -0.4064)
			(stroke
				(width 0.1524)
				(type default)
			)
			(layer "F.SilkS")
		)
		(fp_line
			(start 0.7874 0.4064)
			(end -0.7874 0.4064)
			(stroke
				(width 0.1524)
				(type default)
			)
			(layer "F.SilkS")
		)
		(fp_line
			(start -0.7874 -0.4064)
			(end 0.7874 -0.4064)
			(stroke
				(width 0.1524)
				(type default)
			)
			(layer "F.SilkS")
		)
		(fp_line
			(start 0.7874 -0.4064)
			(end 0.7874 0.4064)
			(stroke
				(width 0.1524)
				(type default)
			)
			(layer "F.SilkS")
		)
		(fp_line
			(start -0.67945 0.3048)
			(end -0.67945 -0.305054)
			(stroke
				(width 0.1)
				(type default)
			)
			(layer "F.Fab")
		)
		(fp_line
			(start -0.12065 0.3048)
			(end -0.67945 0.3048)
			(stroke
				(width 0.1)
				(type default)
			)
			(layer "F.Fab")
		)
		(fp_line
			(start 0.120396 0.3048)
			(end 0.120396 0.2794)
			(stroke
				(width 0.1)
				(type default)
			)
			(layer "F.Fab")
		)
		(fp_line
			(start 0.67945 0.3048)
			(end 0.120396 0.3048)
			(stroke
				(width 0.1)
				(type default)
			)
			(layer "F.Fab")
		)
		(fp_line
			(start -0.12065 0.2794)
			(end -0.12065 0.3048)
			(stroke
				(width 0.1)
				(type default)
			)
			(layer "F.Fab")
		)
		(fp_line
			(start 0.120396 0.2794)
			(end -0.12065 0.2794)
			(stroke
				(width 0.1)
				(type default)
			)
			(layer "F.Fab")
		)
		(fp_line
			(start -0.12065 -0.2794)
			(end 0.12065 -0.2794)
			(stroke
				(width 0.1)
				(type default)
			)
			(layer "F.Fab")
		)
		(fp_line
			(start 0.12065 -0.2794)
			(end 0.12065 -0.3048)
			(stroke
				(width 0.1)
				(type default)
			)
			(layer "F.Fab")
		)
		(fp_line
			(start 0.12065 -0.3048)
			(end 0.67945 -0.3048)
			(stroke
				(width 0.1)
				(type default)
			)
			(layer "F.Fab")
		)
		(fp_line
			(start 0.67945 -0.3048)
			(end 0.67945 0.3048)
			(stroke
				(width 0.1)
				(type default)
			)
			(layer "F.Fab")
		)
		(fp_line
			(start -0.67945 -0.305054)
			(end -0.12065 -0.305054)
			(stroke
				(width 0.1)
				(type default)
			)
			(layer "F.Fab")
		)
		(fp_line
			(start -0.12065 -0.305054)
			(end -0.12065 -0.2794)
			(stroke
				(width 0.1)
				(type default)
			)
			(layer "F.Fab")
		)
		(pad "1" smd circle
			(at -0.40005 0 270)
			(size 0 0)
			(layers "F.Cu" "F.Mask" "F.Paste")
			(net "P3V3_USB_8042")
		)
		(pad "2" smd circle
			(at 0.40005 0 270)
			(size 0 0)
			(layers "F.Cu" "F.Mask" "F.Paste")
			(net "BIC_USB_8042_HUB_PWRCTL2")
		)
	)
	(footprint ""
		(layer "F.Cu")
		(at 228.197156 -274.768056 180)
		(property "Reference" "R788"
			(at 0 0 180)
			(layer "F.SilkS")
			(hide yes)
			(effects
				(font
					(size 1.27 1.27)
				)
			)
		)
		(property "Value" ""
			(at 0 0 180)
			(layer "F.Fab")
			(effects
				(font
					(size 1.27 1.27)
				)
			)
		)
		(duplicate_pad_numbers_are_jumpers no)
		(fp_line
			(start 0.7874 0.4064)
			(end -0.7874 0.4064)
			(stroke
				(width 0.1524)
				(type default)
			)
			(layer "F.SilkS")
		)
		(fp_line
			(start 0.7874 -0.4064)
			(end 0.7874 0.4064)
			(stroke
				(width 0.1524)
				(type default)
			)
			(layer "F.SilkS")
		)
		(fp_line
			(start -0.7874 0.4064)
			(end -0.7874 -0.4064)
			(stroke
				(width 0.1524)
				(type default)
			)
			(layer "F.SilkS")
		)
		(fp_line
			(start -0.7874 -0.4064)
			(end 0.7874 -0.4064)
			(stroke
				(width 0.1524)
				(type default)
			)
			(layer "F.SilkS")
		)
		(fp_line
			(start 0.67945 0.3048)
			(end 0.120396 0.3048)
			(stroke
				(width 0.1)
				(type default)
			)
			(layer "F.Fab")
		)
		(fp_line
			(start 0.67945 -0.3048)
			(end 0.67945 0.3048)
			(stroke
				(width 0.1)
				(type default)
			)
			(layer "F.Fab")
		)
		(fp_line
			(start 0.12065 -0.2794)
			(end 0.12065 -0.3048)
			(stroke
				(width 0.1)
				(type default)
			)
			(layer "F.Fab")
		)
		(fp_line
			(start 0.12065 -0.3048)
			(end 0.67945 -0.3048)
			(stroke
				(width 0.1)
				(type default)
			)
			(layer "F.Fab")
		)
		(fp_line
			(start 0.120396 0.3048)
			(end 0.120396 0.2794)
			(stroke
				(width 0.1)
				(type default)
			)
			(layer "F.Fab")
		)
		(fp_line
			(start 0.120396 0.2794)
			(end -0.12065 0.2794)
			(stroke
				(width 0.1)
				(type default)
			)
			(layer "F.Fab")
		)
		(fp_line
			(start -0.12065 0.3048)
			(end -0.67945 0.3048)
			(stroke
				(width 0.1)
				(type default)
			)
			(layer "F.Fab")
		)
		(fp_line
			(start -0.12065 0.2794)
			(end -0.12065 0.3048)
			(stroke
				(width 0.1)
				(type default)
			)
			(layer "F.Fab")
		)
		(fp_line
			(start -0.12065 -0.2794)
			(end 0.12065 -0.2794)
			(stroke
				(width 0.1)
				(type default)
			)
			(layer "F.Fab")
		)
		(fp_line
			(start -0.12065 -0.305054)
			(end -0.12065 -0.2794)
			(stroke
				(width 0.1)
				(type default)
			)
			(layer "F.Fab")
		)
		(fp_line
			(start -0.67945 0.3048)
			(end -0.67945 -0.305054)
			(stroke
				(width 0.1)
				(type default)
			)
			(layer "F.Fab")
		)
		(fp_line
			(start -0.67945 -0.305054)
			(end -0.12065 -0.305054)
			(stroke
				(width 0.1)
				(type default)
			)
			(layer "F.Fab")
		)
		(pad "1" smd circle
			(at -0.40005 0 180)
			(size 0 0)
			(layers "F.Cu" "F.Mask" "F.Paste")
			(net "P1V25_PEX1_R")
		)
		(pad "2" smd circle
			(at 0.40005 0 180)
			(size 0 0)
			(layers "F.Cu" "F.Mask" "F.Paste")
			(net "P12V_PEX1_P1V25_VIN_P")
		)
	)
	(footprint ""
		(layer "F.Cu")
		(at 216.74709 -54.3941)
		(property "Reference" "PU37"
			(at -1.670812 2.939034 0)
			(unlocked yes)
			(layer "F.SilkS")
			(effects
				(font
					(size 0.7874 0.5842)
					(thickness 0.1524)
				)
				(justify left)
			)
		)
		(property "Value" ""
			(at 0 0 0)
			(layer "F.Fab")
			(effects
				(font
					(size 1.27 1.27)
				)
			)
		)
		(duplicate_pad_numbers_are_jumpers no)
		(fp_line
			(start -1.943608 -1.549908)
			(end 1.943608 -1.549908)
			(stroke
				(width 0.1524)
				(type default)
			)
			(layer "F.SilkS")
		)
		(fp_line
			(start -1.943608 1.549908)
			(end -1.943608 -1.549908)
			(stroke
				(width 0.1524)
				(type default)
			)
			(layer "F.SilkS")
		)
		(fp_line
			(start 1.943608 -1.549908)
			(end 1.943608 1.549908)
			(stroke
				(width 0.1524)
				(type default)
			)
			(layer "F.SilkS")
		)
		(fp_line
			(start 1.943608 1.549908)
			(end -1.943608 1.549908)
			(stroke
				(width 0.1524)
				(type default)
			)
			(layer "F.SilkS")
		)
		(fp_poly
			(pts
				(xy -2.019808 -1.549908) (xy -1.257808 -1.549908) (xy -1.257808 -1.880108) (xy -2.019808 -1.880108)
			)
			(stroke
				(width 0)
				(type default)
			)
			(fill yes)
			(layer "F.SilkS")
		)
		(fp_line
			(start -1.549908 -1.549908)
			(end 1.549908 -1.549908)
			(stroke
				(width 0.1)
				(type default)
			)
			(layer "F.Fab")
		)
		(fp_line
			(start -1.549908 1.549908)
			(end -1.549908 -1.549908)
			(stroke
				(width 0.1)
				(type default)
			)
			(layer "F.Fab")
		)
		(fp_line
			(start 1.549908 -1.549908)
			(end 1.549908 1.549908)
			(stroke
				(width 0.1)
				(type default)
			)
			(layer "F.Fab")
		)
		(fp_line
			(start 1.549908 1.549908)
			(end -1.549908 1.549908)
			(stroke
				(width 0.1)
				(type default)
			)
			(layer "F.Fab")
		)
		(fp_poly
			(pts
				(xy -2.019808 -1.549908) (xy -1.257808 -1.549908) (xy -1.257808 -1.880108) (xy -2.019808 -1.880108)
			)
			(stroke
				(width 0)
				(type default)
			)
			(fill yes)
			(layer "F.Fab")
		)
		(pad "1" smd rect
			(at -1.500124 -1.249934 270)
			(size 0.2794 0.6096)
			(layers "F.Cu" "F.Mask" "F.Paste")
			(net "P12V_SSD7_R")
		)
		(pad "2" smd rect
			(at -1.500124 -0.750062 270)
			(size 0.2794 0.6096)
			(layers "F.Cu" "F.Mask" "F.Paste")
			(net "P12V_SSD7_R")
		)
		(pad "3" smd rect
			(at -1.500124 -0.249936 270)
			(size 0.2794 0.6096)
			(layers "F.Cu" "F.Mask" "F.Paste")
			(net "P12V_SSD7_R")
		)
		(pad "4" smd rect
			(at -1.500124 0.249936 270)
			(size 0.2794 0.6096)
			(layers "F.Cu" "F.Mask" "F.Paste")
			(net "P12V_SSD7_R")
		)
		(pad "5" smd rect
			(at -1.500124 0.750062 270)
			(size 0.2794 0.6096)
			(layers "F.Cu" "F.Mask" "F.Paste")
			(net "P12V_SSD7_R")
		)
		(pad "6" smd rect
			(at -1.500124 1.249934 270)
			(size 0.2794 0.6096)
			(layers "F.Cu" "F.Mask" "F.Paste")
			(net "GND")
		)
		(pad "7" smd rect
			(at 1.500124 1.249934 270)
			(size 0.2794 0.6096)
			(layers "F.Cu" "F.Mask" "F.Paste")
			(net "P12V_SSD7_SS")
		)
		(pad "8" smd rect
			(at 1.500124 0.750062 270)
			(size 0.2794 0.6096)
			(layers "F.Cu" "F.Mask" "F.Paste")
			(net "PWRGD_P12V_SSD7")
		)
		(pad "9" smd rect
			(at 1.500124 0.249936 270)
			(size 0.2794 0.6096)
			(layers "F.Cu" "F.Mask" "F.Paste")
			(net "P12V_SSD7_OCP")
		)
		(pad "10" smd rect
			(at 1.500124 -0.249936 270)
			(size 0.2794 0.6096)
			(layers "F.Cu" "F.Mask" "F.Paste")
			(net "P5V_AUX")
		)
		(pad "11" smd rect
			(at 1.500124 -0.750062 270)
			(size 0.2794 0.6096)
			(layers "F.Cu" "F.Mask" "F.Paste")
			(net "SSD7_PWR_EN_R")
		)
		(pad "12" smd rect
			(at 1.500124 -1.249934 270)
			(size 0.2794 0.6096)
			(layers "F.Cu" "F.Mask" "F.Paste")
			(net "P12V_AUX")
		)
		(pad "13" smd rect
			(at 0 0)
			(size 1.9812 2.7178)
			(layers "F.Cu" "F.Mask" "F.Paste")
			(net "P12V_AUX")
		)
		(zone
			(layer "F.Cu")
			(hatch none 0.5)
			(connect_pads
				(clearance 0)
			)
			(min_thickness 0.25)
			(keepout
				(tracks not_allowed)
				(vias allowed)
				(pads allowed)
				(copperpour not_allowed)
				(footprints allowed)
			)
			(placement
				(enabled no)
				(sheetname "")
			)
			(fill
				(thermal_gap 0.5)
				(thermal_bridge_width 0.5)
				(island_removal_mode 0)
			)
			(polygon
				(pts
					(xy 217.89009 -55.9435) (xy 217.89009 -55.8165) (xy 217.89009 -52.8447) (xy 217.89009 -52.844192)
					(xy 215.60409 -52.844192) (xy 215.60409 -52.8447) (xy 215.60409 -52.9717) (xy 215.60409 -54.3941)
					(xy 215.70569 -54.3941) (xy 215.70569 -52.9717) (xy 217.78849 -52.9717) (xy 217.78849 -55.8165)
					(xy 215.70569 -55.8165) (xy 215.70569 -54.4195) (xy 215.60409 -54.4195) (xy 215.60409 -55.8165)
					(xy 215.60409 -55.9435) (xy 215.60409 -55.944008) (xy 217.89009 -55.944008)
				)
			)
		)
	)
	(footprint ""
		(layer "F.Cu")
		(at 410.184092 -343.952322 90)
		(property "Reference" "C825"
			(at 0 0 90)
			(layer "F.SilkS")
			(hide yes)
			(effects
				(font
					(size 1.27 1.27)
				)
			)
		)
		(property "Value" ""
			(at 0 0 90)
			(layer "F.Fab")
			(effects
				(font
					(size 1.27 1.27)
				)
			)
		)
		(duplicate_pad_numbers_are_jumpers no)
		(fp_line
			(start 0.299974 -0.150114)
			(end 0.299974 0.150114)
			(stroke
				(width 0.1)
				(type default)
			)
			(layer "F.Fab")
		)
		(fp_line
			(start -0.299974 -0.150114)
			(end 0.299974 -0.150114)
			(stroke
				(width 0.1)
				(type default)
			)
			(layer "F.Fab")
		)
		(fp_line
			(start 0.299974 0.150114)
			(end -0.299974 0.150114)
			(stroke
				(width 0.1)
				(type default)
			)
			(layer "F.Fab")
		)
		(fp_line
			(start -0.299974 0.150114)
			(end -0.299974 -0.150114)
			(stroke
				(width 0.1)
				(type default)
			)
			(layer "F.Fab")
		)
		(pad "1" smd rect
			(at -0.2667 0 90)
			(size 0.3048 0.381)
			(layers "F.Cu" "F.Mask" "F.Paste")
			(net "P5E_PEX3_STN7_TX_DN<112>")
		)
		(pad "2" smd rect
			(at 0.2667 0 90)
			(size 0.3048 0.381)
			(layers "F.Cu" "F.Mask" "F.Paste")
			(net "P5E_PEX3_STN7_TX_C_DN<112>")
		)
	)
	(footprint ""
		(layer "F.Cu")
		(at 20.659598 -61.612526)
		(property "Reference" "PD21"
			(at -3.7084 -2.733548 0)
			(unlocked yes)
			(layer "F.SilkS")
			(effects
				(font
					(size 0.7874 0.5842)
					(thickness 0.1524)
				)
				(justify left)
			)
		)
		(property "Value" ""
			(at 0 0 0)
			(layer "F.Fab")
			(effects
				(font
					(size 1.27 1.27)
				)
			)
		)
		(duplicate_pad_numbers_are_jumpers no)
		(fp_line
			(start -3.656584 -1.970024)
			(end -3.656584 1.970024)
			(stroke
				(width 0.1524)
				(type default)
			)
			(layer "F.SilkS")
		)
		(fp_line
			(start -3.656584 1.970024)
			(end 4.240784 1.970024)
			(stroke
				(width 0.1524)
				(type default)
			)
			(layer "F.SilkS")
		)
		(fp_line
			(start 4.240784 -1.970024)
			(end -3.656584 -1.970024)
			(stroke
				(width 0.1524)
				(type default)
			)
			(layer "F.SilkS")
		)
		(fp_line
			(start 4.240784 1.970024)
			(end 4.240784 -1.970024)
			(stroke
				(width 0.1524)
				(type default)
			)
			(layer "F.SilkS")
		)
		(fp_poly
			(pts
				(xy 3.580384 1.970024) (xy 3.580384 -1.970024) (xy 4.240784 -1.970024) (xy 4.240784 1.970024)
			)
			(stroke
				(width 0)
				(type default)
			)
			(fill yes)
			(layer "F.SilkS")
		)
		(fp_line
			(start -2.3749 -1.970024)
			(end -2.3749 1.970024)
			(stroke
				(width 0.1)
				(type default)
			)
			(layer "F.Fab")
		)
		(fp_line
			(start -2.3749 1.970024)
			(end 2.3749 1.970024)
			(stroke
				(width 0.1)
				(type default)
			)
			(layer "F.Fab")
		)
		(fp_line
			(start 2.3749 -1.970024)
			(end -2.3749 -1.970024)
			(stroke
				(width 0.1)
				(type default)
			)
			(layer "F.Fab")
		)
		(fp_line
			(start 2.3749 1.970024)
			(end 2.3749 -1.970024)
			(stroke
				(width 0.1)
				(type default)
			)
			(layer "F.Fab")
		)
		(fp_text user "+"
			(at -4.9784 -0.23495 0)
			(unlocked yes)
			(layer "F.Fab")
			(effects
				(font
					(size 1.905 1.4224)
					(thickness 0.1524)
				)
				(justify left)
			)
		)
		(fp_text user "-"
			(at 4.1656 -0.23495 0)
			(unlocked yes)
			(layer "F.Fab")
			(effects
				(font
					(size 1.905 1.4224)
					(thickness 0.1524)
				)
				(justify left)
			)
		)
		(pad "A" smd rect
			(at -2.450084 0)
			(size 2.159 2.2606)
			(layers "F.Cu" "F.Mask" "F.Paste")
			(net "GND")
		)
		(pad "C" smd rect
			(at 2.450084 0)
			(size 2.159 2.2606)
			(layers "F.Cu" "F.Mask" "F.Paste")
			(net "P12V_AUX")
		)
	)
	(footprint ""
		(layer "F.Cu")
		(at 440.258708 -111.227108 90)
		(property "Reference" "PC824"
			(at 0 0 90)
			(layer "F.SilkS")
			(hide yes)
			(effects
				(font
					(size 1.27 1.27)
				)
			)
		)
		(property "Value" ""
			(at 0 0 90)
			(layer "F.Fab")
			(effects
				(font
					(size 1.27 1.27)
				)
			)
		)
		(duplicate_pad_numbers_are_jumpers no)
		(fp_line
			(start 1.524 -0.762)
			(end 1.524 0.762)
			(stroke
				(width 0.1524)
				(type default)
			)
			(layer "F.SilkS")
		)
		(fp_line
			(start -1.524 -0.762)
			(end 1.524 -0.762)
			(stroke
				(width 0.1524)
				(type default)
			)
			(layer "F.SilkS")
		)
		(fp_line
			(start 1.524 0.762)
			(end -1.524 0.762)
			(stroke
				(width 0.1524)
				(type default)
			)
			(layer "F.SilkS")
		)
		(fp_line
			(start -1.524 0.762)
			(end -1.524 -0.762)
			(stroke
				(width 0.1524)
				(type default)
			)
			(layer "F.SilkS")
		)
		(fp_line
			(start 1.1049 -0.724916)
			(end -1.1049 -0.724916)
			(stroke
				(width 0.1)
				(type default)
			)
			(layer "F.Fab")
		)
		(fp_line
			(start -1.1049 -0.724916)
			(end -1.1049 0.724916)
			(stroke
				(width 0.1)
				(type default)
			)
			(layer "F.Fab")
		)
		(fp_line
			(start 1.1049 0.724916)
			(end 1.1049 -0.724916)
			(stroke
				(width 0.1)
				(type default)
			)
			(layer "F.Fab")
		)
		(fp_line
			(start -1.1049 0.724916)
			(end 1.1049 0.724916)
			(stroke
				(width 0.1)
				(type default)
			)
			(layer "F.Fab")
		)
		(pad "1" smd rect
			(at -0.889 0 270)
			(size 1.016 1.27)
			(layers "F.Cu" "F.Mask" "F.Paste")
			(net "P12V_NIC7_R")
		)
		(pad "2" smd rect
			(at 0.889 0 270)
			(size 1.016 1.27)
			(layers "F.Cu" "F.Mask" "F.Paste")
			(net "GND")
		)
	)
	(footprint ""
		(layer "F.Cu")
		(at 324.913244 -350.098614 90)
		(property "Reference" "C537"
			(at 0 0 90)
			(layer "F.SilkS")
			(hide yes)
			(effects
				(font
					(size 1.27 1.27)
				)
			)
		)
		(property "Value" ""
			(at 0 0 90)
			(layer "F.Fab")
			(effects
				(font
					(size 1.27 1.27)
				)
			)
		)
		(duplicate_pad_numbers_are_jumpers no)
		(fp_line
			(start 0.299974 -0.150114)
			(end 0.299974 0.150114)
			(stroke
				(width 0.1)
				(type default)
			)
			(layer "F.Fab")
		)
		(fp_line
			(start -0.299974 -0.150114)
			(end 0.299974 -0.150114)
			(stroke
				(width 0.1)
				(type default)
			)
			(layer "F.Fab")
		)
		(fp_line
			(start 0.299974 0.150114)
			(end -0.299974 0.150114)
			(stroke
				(width 0.1)
				(type default)
			)
			(layer "F.Fab")
		)
		(fp_line
			(start -0.299974 0.150114)
			(end -0.299974 -0.150114)
			(stroke
				(width 0.1)
				(type default)
			)
			(layer "F.Fab")
		)
		(pad "1" smd rect
			(at -0.2667 0 90)
			(size 0.3048 0.381)
			(layers "F.Cu" "F.Mask" "F.Paste")
			(net "P5E_PEX2_STN5_TX_DP<86>")
		)
		(pad "2" smd rect
			(at 0.2667 0 90)
			(size 0.3048 0.381)
			(layers "F.Cu" "F.Mask" "F.Paste")
			(net "P5E_PEX2_STN5_TX_C_DP<86>")
		)
	)
)
